(kicad_pcb
	(version 20260206)
	(generator "pcbnew")
	(generator_version "10.0")
	(general
		(thickness 1.6)
		(legacy_teardrops no)
	)
	(paper "A4")
	(title_block
		(title "03242023_DA0F0TMBIJ0_F0T_Motherboard_J_brd_V01_OCP.brd")
		(comment 1 "Grand Teton / footprints 2951-2953 of 6105")
	)
	(layers
		(0 "F.Cu" signal "TOP")
		(4 "In1.Cu" signal "GND")
		(6 "In2.Cu" signal "IN1")
		(8 "In3.Cu" signal "GND1")
		(10 "In4.Cu" signal "IN2")
		(12 "In5.Cu" signal "GND2")
		(14 "In6.Cu" signal "IN3")
		(16 "In7.Cu" signal "GND3")
		(18 "In8.Cu" signal "VCC")
		(20 "In9.Cu" signal "VCC1")
		(22 "In10.Cu" signal "GND4")
		(24 "In11.Cu" signal "IN4")
		(26 "In12.Cu" signal "GND5")
		(28 "In13.Cu" signal "IN5")
		(30 "In14.Cu" signal "GND6")
		(32 "In15.Cu" signal "IN6")
		(34 "In16.Cu" signal "GND7")
		(2 "B.Cu" signal "BOTTOM")
		(9 "F.Adhes" user "F.Adhesive")
		(11 "B.Adhes" user "B.Adhesive")
		(13 "F.Paste" user "Package Geometry/Pastemask Top")
		(15 "B.Paste" user "Package Geometry/Pastemask Bottom")
		(5 "F.SilkS" user "Ref Des/Silkscreen Top")
		(7 "B.SilkS" user "Ref Des/Silkscreen Bottom")
		(1 "F.Mask" user "Board Geometry/Soldermask Top")
		(3 "B.Mask" user "Board Geometry/Soldermask Bottom")
		(17 "Dwgs.User" user "User.Drawings")
		(19 "Cmts.User" user "User.Comments")
		(21 "Eco1.User" user "User.Eco1")
		(23 "Eco2.User" user "User.Eco2")
		(25 "Edge.Cuts" user "Board Geometry/Outline")
		(27 "Margin" user)
		(31 "F.CrtYd" user "Package Geometry/Place Bound Top")
		(29 "B.CrtYd" user "Package Geometry/Place Bound Bottom")
		(35 "F.Fab" user "Ref Des/Assembly Top")
		(33 "B.Fab" user "Ref Des/Assembly Bottom")
	)
	(footprint ""
		(layer "F.Cu")
		(at 21.913596 -390.675876 90)
		(property "Reference" "U237"
			(at -6.036056 -6.165088 0)
			(unlocked yes)
			(layer "F.SilkS")
			(effects
				(font
					(size 0.7874 0.5842)
					(thickness 0.1524)
				)
				(justify left)
			)
		)
		(property "Value" ""
			(at 0 0 90)
			(layer "F.Fab")
			(effects
				(font
					(size 1.27 1.27)
				)
			)
		)
		(duplicate_pad_numbers_are_jumpers no)
		(fp_line
			(start -0.8128 -2.6924)
			(end -0.8128 -3.5052)
			(stroke
				(width 0.1524)
				(type default)
			)
			(layer "F.SilkS")
		)
		(fp_line
			(start 1.299972 -2.29997)
			(end 1.016 -2.29997)
			(stroke
				(width 0.1524)
				(type default)
			)
			(layer "F.SilkS")
		)
		(fp_line
			(start -1.016 -2.29997)
			(end -1.299972 -2.29997)
			(stroke
				(width 0.1524)
				(type default)
			)
			(layer "F.SilkS")
		)
		(fp_line
			(start -1.299972 -2.29997)
			(end -1.299972 -2.015998)
			(stroke
				(width 0.1524)
				(type default)
			)
			(layer "F.SilkS")
		)
		(fp_line
			(start 1.299972 -2.015998)
			(end 1.299972 -2.29997)
			(stroke
				(width 0.1524)
				(type default)
			)
			(layer "F.SilkS")
		)
		(fp_line
			(start 1.6891 -1.8034)
			(end 2.0701 -1.8034)
			(stroke
				(width 0.1524)
				(type default)
			)
			(layer "F.SilkS")
		)
		(fp_line
			(start -1.6891 -0.2032)
			(end -2.0701 -0.2032)
			(stroke
				(width 0.1524)
				(type default)
			)
			(layer "F.SilkS")
		)
		(fp_line
			(start 2.5146 0.2032)
			(end 1.7018 0.2032)
			(stroke
				(width 0.1524)
				(type default)
			)
			(layer "F.SilkS")
		)
		(fp_line
			(start -1.7018 1.8034)
			(end -2.5146 1.8034)
			(stroke
				(width 0.1524)
				(type default)
			)
			(layer "F.SilkS")
		)
		(fp_line
			(start -1.299972 2.015998)
			(end -1.299972 2.29997)
			(stroke
				(width 0.1524)
				(type default)
			)
			(layer "F.SilkS")
		)
		(fp_line
			(start 1.299972 2.29997)
			(end 1.299972 2.015998)
			(stroke
				(width 0.1524)
				(type default)
			)
			(layer "F.SilkS")
		)
		(fp_line
			(start 1.016 2.29997)
			(end 1.299972 2.29997)
			(stroke
				(width 0.1524)
				(type default)
			)
			(layer "F.SilkS")
		)
		(fp_line
			(start -1.299972 2.29997)
			(end -1.016 2.29997)
			(stroke
				(width 0.1524)
				(type default)
			)
			(layer "F.SilkS")
		)
		(fp_line
			(start 0.7874 3.0861)
			(end 0.7874 2.7051)
			(stroke
				(width 0.1524)
				(type default)
			)
			(layer "F.SilkS")
		)
		(fp_poly
			(pts
				(xy -3.111246 -3.900678) (xy -3.829558 -3.182112) (xy -2.75209 -2.822956)
			)
			(stroke
				(width 0)
				(type default)
			)
			(fill yes)
			(layer "F.SilkS")
		)
		(fp_line
			(start -0.8128 -2.6924)
			(end -0.8128 -3.5052)
			(stroke
				(width 0.1)
				(type default)
			)
			(layer "F.Fab")
		)
		(fp_line
			(start 1.299972 -2.29997)
			(end -1.299972 -2.29997)
			(stroke
				(width 0.1)
				(type default)
			)
			(layer "F.Fab")
		)
		(fp_line
			(start -1.299972 -2.29997)
			(end -1.299972 2.29997)
			(stroke
				(width 0.1)
				(type default)
			)
			(layer "F.Fab")
		)
		(fp_line
			(start 1.6891 -1.8034)
			(end 2.0701 -1.8034)
			(stroke
				(width 0.1)
				(type default)
			)
			(layer "F.Fab")
		)
		(fp_line
			(start -1.6891 -0.2032)
			(end -2.0701 -0.2032)
			(stroke
				(width 0.1)
				(type default)
			)
			(layer "F.Fab")
		)
		(fp_line
			(start 2.5146 0.2032)
			(end 1.7018 0.2032)
			(stroke
				(width 0.1)
				(type default)
			)
			(layer "F.Fab")
		)
		(fp_line
			(start -1.7018 1.8034)
			(end -2.5146 1.8034)
			(stroke
				(width 0.1)
				(type default)
			)
			(layer "F.Fab")
		)
		(fp_line
			(start 1.299972 2.29997)
			(end 1.299972 -2.29997)
			(stroke
				(width 0.1)
				(type default)
			)
			(layer "F.Fab")
		)
		(fp_line
			(start -1.299972 2.29997)
			(end 1.299972 2.29997)
			(stroke
				(width 0.1)
				(type default)
			)
			(layer "F.Fab")
		)
		(fp_line
			(start 0.7874 3.0861)
			(end 0.7874 2.7051)
			(stroke
				(width 0.1)
				(type default)
			)
			(layer "F.Fab")
		)
		(fp_poly
			(pts
				(xy -2.7178 -2.308098) (xy -2.7178 -1.292098) (xy -1.7018 -1.800098)
			)
			(stroke
				(width 0)
				(type default)
			)
			(fill yes)
			(layer "F.Fab")
		)
		(fp_text user "26"
			(at 3.089402 -4.626356 0)
			(unlocked yes)
			(layer "F.SilkS")
			(effects
				(font
					(size 0.635 0.4064)
					(thickness 0.1524)
				)
			)
		)
		(fp_text user "25"
			(at 3.871468 -3.175 0)
			(unlocked yes)
			(layer "F.SilkS")
			(effects
				(font
					(size 0.635 0.4064)
					(thickness 0.1524)
				)
			)
		)
		(fp_text user "30"
			(at -2.718816 -2.527808 0)
			(unlocked yes)
			(layer "F.SilkS")
			(effects
				(font
					(size 0.635 0.4064)
					(thickness 0.1524)
				)
			)
		)
		(fp_text user "10"
			(at -4.436872 2.85496 0)
			(unlocked yes)
			(layer "F.SilkS")
			(effects
				(font
					(size 0.635 0.4064)
					(thickness 0.1524)
				)
			)
		)
		(fp_text user "16"
			(at 2.007108 2.98958 0)
			(unlocked yes)
			(layer "F.SilkS")
			(effects
				(font
					(size 0.635 0.4064)
					(thickness 0.1524)
				)
			)
		)
		(fp_text user "11"
			(at -1.746758 4.055364 0)
			(unlocked yes)
			(layer "F.SilkS")
			(effects
				(font
					(size 0.635 0.4064)
					(thickness 0.1524)
				)
			)
		)
		(fp_text user "15"
			(at 1.489964 4.071112 0)
			(unlocked yes)
			(layer "F.SilkS")
			(effects
				(font
					(size 0.635 0.4064)
					(thickness 0.1524)
				)
			)
		)
		(fp_text user "26"
			(at 1.0922 -3.071368 90)
			(unlocked yes)
			(layer "F.Fab")
			(effects
				(font
					(size 0.635 0.4064)
					(thickness 0.1524)
				)
			)
		)
		(fp_text user "30"
			(at -1.4478 -2.842768 90)
			(unlocked yes)
			(layer "F.Fab")
			(effects
				(font
					(size 0.635 0.4064)
					(thickness 0.1524)
				)
			)
		)
		(fp_text user "25"
			(at 1.979168 -2.4384 0)
			(unlocked yes)
			(layer "F.Fab")
			(effects
				(font
					(size 0.635 0.4064)
					(thickness 0.1524)
				)
			)
		)
		(fp_text user "16"
			(at 2.029968 2.0574 0)
			(unlocked yes)
			(layer "F.Fab")
			(effects
				(font
					(size 0.635 0.4064)
					(thickness 0.1524)
				)
			)
		)
		(fp_text user "10"
			(at -2.084832 2.3876 0)
			(unlocked yes)
			(layer "F.Fab")
			(effects
				(font
					(size 0.635 0.4064)
					(thickness 0.1524)
				)
			)
		)
		(fp_text user "15"
			(at 1.3716 2.948432 90)
			(unlocked yes)
			(layer "F.Fab")
			(effects
				(font
					(size 0.635 0.4064)
					(thickness 0.1524)
				)
			)
		)
		(fp_text user "11"
			(at -1.2192 3.075432 90)
			(unlocked yes)
			(layer "F.Fab")
			(effects
				(font
					(size 0.635 0.4064)
					(thickness 0.1524)
				)
			)
		)
		(pad "1" smd circle
			(at -1.249934 -1.800098)
			(size 0 0)
			(layers "F.Cu" "F.Mask" "F.Paste")
			(net "P3V3_AUX")
		)
		(pad "2" smd circle
			(at -1.249934 -1.400048)
			(size 0 0)
			(layers "F.Cu" "F.Mask" "F.Paste")
			(net "P2E_MB_BMC_TX_C_R1_DP<0>")
		)
		(pad "3" smd circle
			(at -1.249934 -0.999998)
			(size 0 0)
			(layers "F.Cu" "F.Mask" "F.Paste")
			(net "P2E_MB_BMC_TX_C_R1_DN<0>")
		)
		(pad "4" smd circle
			(at -1.249934 -0.599948)
			(size 0 0)
			(layers "F.Cu" "F.Mask" "F.Paste")
			(net "GND")
		)
		(pad "5" smd circle
			(at -1.249934 -0.199898)
			(size 0 0)
			(layers "F.Cu" "F.Mask" "F.Paste")
			(net "PU_TEST")
		)
		(pad "6" smd circle
			(at -1.249934 0.199898)
			(size 0 0)
			(layers "F.Cu" "F.Mask" "F.Paste")
			(net "GND")
		)
		(pad "7" smd circle
			(at -1.249934 0.599948)
			(size 0 0)
			(layers "F.Cu" "F.Mask" "F.Paste")
			(net "GND")
		)
		(pad "8" smd circle
			(at -1.249934 0.999998)
			(size 0 0)
			(layers "F.Cu" "F.Mask" "F.Paste")
			(net "P2E_MB_BMC_RX_BUF_C_DN<0>")
		)
		(pad "9" smd circle
			(at -1.249934 1.400048)
			(size 0 0)
			(layers "F.Cu" "F.Mask" "F.Paste")
			(net "P2E_MB_BMC_RX_BUF_C_DP<0>")
		)
		(pad "10" smd circle
			(at -1.249934 1.800098)
			(size 0 0)
			(layers "F.Cu" "F.Mask" "F.Paste")
			(net "P3V3_AUX")
		)
		(pad "11" smd circle
			(at -0.8001 2.249932 90)
			(size 0 0)
			(layers "F.Cu" "F.Mask" "F.Paste")
			(net "FM_P2E_EN_N")
		)
		(pad "12" smd circle
			(at -0.40005 2.249932 90)
			(size 0 0)
			(layers "F.Cu" "F.Mask" "F.Paste")
			(net "FM_P2E_SWB")
		)
		(pad "13" smd circle
			(at 0 2.249932 90)
			(size 0 0)
			(layers "F.Cu" "F.Mask" "F.Paste")
			(net "GND")
		)
		(pad "14" smd circle
			(at 0.40005 2.249932 90)
			(size 0 0)
			(layers "F.Cu" "F.Mask" "F.Paste")
			(net "FM_P2E_FGB")
		)
		(pad "15" smd circle
			(at 0.8001 2.249932 90)
			(size 0 0)
			(layers "F.Cu" "F.Mask" "F.Paste")
			(net "FM_P2E_EQB1")
		)
		(pad "16" smd circle
			(at 1.249934 1.800098 180)
			(size 0 0)
			(layers "F.Cu" "F.Mask" "F.Paste")
			(net "P3V3_AUX")
		)
		(pad "17" smd circle
			(at 1.249934 1.400048 180)
			(size 0 0)
			(layers "F.Cu" "F.Mask" "F.Paste")
			(net "P2E_MB_BMC_RX_R1_DP<0>")
		)
		(pad "18" smd circle
			(at 1.249934 0.999998 180)
			(size 0 0)
			(layers "F.Cu" "F.Mask" "F.Paste")
			(net "P2E_MB_BMC_RX_R1_DN<0>")
		)
		(pad "19" smd circle
			(at 1.249934 0.599948 180)
			(size 0 0)
			(layers "F.Cu" "F.Mask" "F.Paste")
			(net "GND")
		)
		(pad "20" smd circle
			(at 1.249934 0.199898 180)
			(size 0 0)
			(layers "F.Cu" "F.Mask" "F.Paste")
			(net "FM_P2E_EQB0")
		)
		(pad "21" smd circle
			(at 1.249934 -0.199898 180)
			(size 0 0)
			(layers "F.Cu" "F.Mask" "F.Paste")
			(net "FM_P2E_EQA0")
		)
		(pad "22" smd circle
			(at 1.249934 -0.599948 180)
			(size 0 0)
			(layers "F.Cu" "F.Mask" "F.Paste")
			(net "GND")
		)
		(pad "23" smd circle
			(at 1.249934 -0.999998 180)
			(size 0 0)
			(layers "F.Cu" "F.Mask" "F.Paste")
			(net "P2E_MB_BMC_TX_BUF_DN<0>")
		)
		(pad "24" smd circle
			(at 1.249934 -1.400048 180)
			(size 0 0)
			(layers "F.Cu" "F.Mask" "F.Paste")
			(net "P2E_MB_BMC_TX_BUF_DP<0>")
		)
		(pad "25" smd circle
			(at 1.249934 -1.800098 180)
			(size 0 0)
			(layers "F.Cu" "F.Mask" "F.Paste")
			(net "P3V3_AUX")
		)
		(pad "26" smd circle
			(at 0.8001 -2.249932 270)
			(size 0 0)
			(layers "F.Cu" "F.Mask" "F.Paste")
			(net "FM_P2E_EQA1")
		)
		(pad "27" smd circle
			(at 0.40005 -2.249932 270)
			(size 0 0)
			(layers "F.Cu" "F.Mask" "F.Paste")
			(net "FM_P2E_FGA")
		)
		(pad "28" smd circle
			(at 0 -2.249932 270)
			(size 0 0)
			(layers "F.Cu" "F.Mask" "F.Paste")
			(net "GND")
		)
		(pad "29" smd circle
			(at -0.40005 -2.249932 270)
			(size 0 0)
			(layers "F.Cu" "F.Mask" "F.Paste")
			(net "FM_P2E_SWA")
		)
		(pad "30" smd circle
			(at -0.8001 -2.249932 270)
			(size 0 0)
			(layers "F.Cu" "F.Mask" "F.Paste")
			(net "FM_P2E_MODE")
		)
		(pad "TH" smd rect
			(at 0 0 90)
			(size 1.2192 3.2004)
			(layers "F.Cu" "F.Mask" "F.Paste")
			(net "GND")
		)
		(zone
			(layer "F.Cu")
			(hatch none 0.5)
			(connect_pads
				(clearance 0)
			)
			(min_thickness 0.25)
			(keepout
				(tracks not_allowed)
				(vias allowed)
				(pads allowed)
				(copperpour not_allowed)
				(footprints allowed)
			)
			(placement
				(enabled no)
				(sheetname "")
			)
			(fill
				(thermal_gap 0.5)
				(thermal_bridge_width 0.5)
				(island_removal_mode 0)
			)
			(polygon
				(pts
					(xy 20.033996 -390.853676) (xy 20.262596 -390.853676) (xy 20.262596 -390.015476) (xy 23.564596 -390.015476)
					(xy 23.564596 -391.336276) (xy 20.262596 -391.336276) (xy 20.262596 -390.879076) (xy 20.033996 -390.879076)
					(xy 20.033996 -391.564876) (xy 23.793196 -391.564876) (xy 23.793196 -389.786876) (xy 20.033996 -389.786876)
				)
			)
		)
	)
	(footprint ""
		(layer "F.Cu")
		(at 73.94448 -161.107882 180)
		(property "Reference" "PR559"
			(at 0 0 180)
			(layer "F.SilkS")
			(hide yes)
			(effects
				(font
					(size 1.27 1.27)
				)
			)
		)
		(property "Value" ""
			(at 0 0 180)
			(layer "F.Fab")
			(effects
				(font
					(size 1.27 1.27)
				)
			)
		)
		(duplicate_pad_numbers_are_jumpers no)
		(fp_line
			(start 0.7874 0.4064)
			(end -0.7874 0.4064)
			(stroke
				(width 0.1524)
				(type default)
			)
			(layer "F.SilkS")
		)
		(fp_line
			(start 0.7874 -0.4064)
			(end 0.7874 0.4064)
			(stroke
				(width 0.1524)
				(type default)
			)
			(layer "F.SilkS")
		)
		(fp_line
			(start -0.7874 0.4064)
			(end -0.7874 -0.4064)
			(stroke
				(width 0.1524)
				(type default)
			)
			(layer "F.SilkS")
		)
		(fp_line
			(start -0.7874 -0.4064)
			(end 0.7874 -0.4064)
			(stroke
				(width 0.1524)
				(type default)
			)
			(layer "F.SilkS")
		)
		(fp_line
			(start 0.67945 0.3048)
			(end 0.120396 0.3048)
			(stroke
				(width 0.1)
				(type default)
			)
			(layer "F.Fab")
		)
		(fp_line
			(start 0.67945 -0.3048)
			(end 0.67945 0.3048)
			(stroke
				(width 0.1)
				(type default)
			)
			(layer "F.Fab")
		)
		(fp_line
			(start 0.12065 -0.2794)
			(end 0.12065 -0.3048)
			(stroke
				(width 0.1)
				(type default)
			)
			(layer "F.Fab")
		)
		(fp_line
			(start 0.12065 -0.3048)
			(end 0.67945 -0.3048)
			(stroke
				(width 0.1)
				(type default)
			)
			(layer "F.Fab")
		)
		(fp_line
			(start 0.120396 0.3048)
			(end 0.120396 0.2794)
			(stroke
				(width 0.1)
				(type default)
			)
			(layer "F.Fab")
		)
		(fp_line
			(start 0.120396 0.2794)
			(end -0.12065 0.2794)
			(stroke
				(width 0.1)
				(type default)
			)
			(layer "F.Fab")
		)
		(fp_line
			(start -0.12065 0.3048)
			(end -0.67945 0.3048)
			(stroke
				(width 0.1)
				(type default)
			)
			(layer "F.Fab")
		)
		(fp_line
			(start -0.12065 0.2794)
			(end -0.12065 0.3048)
			(stroke
				(width 0.1)
				(type default)
			)
			(layer "F.Fab")
		)
		(fp_line
			(start -0.12065 -0.2794)
			(end 0.12065 -0.2794)
			(stroke
				(width 0.1)
				(type default)
			)
			(layer "F.Fab")
		)
		(fp_line
			(start -0.12065 -0.305054)
			(end -0.12065 -0.2794)
			(stroke
				(width 0.1)
				(type default)
			)
			(layer "F.Fab")
		)
		(fp_line
			(start -0.67945 0.3048)
			(end -0.67945 -0.305054)
			(stroke
				(width 0.1)
				(type default)
			)
			(layer "F.Fab")
		)
		(fp_line
			(start -0.67945 -0.305054)
			(end -0.12065 -0.305054)
			(stroke
				(width 0.1)
				(type default)
			)
			(layer "F.Fab")
		)
		(pad "1" smd circle
			(at -0.40005 0 180)
			(size 0 0)
			(layers "F.Cu" "F.Mask" "F.Paste")
			(net "VSENSE_PVCCD_HV_CPU1_DP")
		)
		(pad "2" smd circle
			(at 0.40005 0 180)
			(size 0 0)
			(layers "F.Cu" "F.Mask" "F.Paste")
			(net "PVCCD_HV_CPU1")
		)
	)
	(footprint ""
		(layer "F.Cu")
		(at 119.508016 -260.36524 -90)
		(property "Reference" "C432"
			(at 0 0 270)
			(layer "F.SilkS")
			(hide yes)
			(effects
				(font
					(size 1.27 1.27)
				)
			)
		)
		(property "Value" ""
			(at 0 0 270)
			(layer "F.Fab")
			(effects
				(font
					(size 1.27 1.27)
				)
			)
		)
		(duplicate_pad_numbers_are_jumpers no)
		(fp_line
			(start -0.7874 0.4064)
			(end -0.7874 -0.4064)
			(stroke
				(width 0.1524)
				(type default)
			)
			(layer "F.SilkS")
		)
		(fp_line
			(start 0.7874 0.4064)
			(end -0.7874 0.4064)
			(stroke
				(width 0.1524)
				(type default)
			)
			(layer "F.SilkS")
		)
		(fp_line
			(start -0.7874 -0.4064)
			(end 0.7874 -0.4064)
			(stroke
				(width 0.1524)
				(type default)
			)
			(layer "F.SilkS")
		)
		(fp_line
			(start 0.7874 -0.4064)
			(end 0.7874 0.4064)
			(stroke
				(width 0.1524)
				(type default)
			)
			(layer "F.SilkS")
		)
		(fp_line
			(start -0.67945 0.3048)
			(end -0.67945 -0.305054)
			(stroke
				(width 0.1)
				(type default)
			)
			(layer "F.Fab")
		)
		(fp_line
			(start -0.12065 0.3048)
			(end -0.67945 0.3048)
			(stroke
				(width 0.1)
				(type default)
			)
			(layer "F.Fab")
		)
		(fp_line
			(start 0.120396 0.3048)
			(end 0.120396 0.2794)
			(stroke
				(width 0.1)
				(type default)
			)
			(layer "F.Fab")
		)
		(fp_line
			(start 0.67945 0.3048)
			(end 0.120396 0.3048)
			(stroke
				(width 0.1)
				(type default)
			)
			(layer "F.Fab")
		)
		(fp_line
			(start -0.12065 0.2794)
			(end -0.12065 0.3048)
			(stroke
				(width 0.1)
				(type default)
			)
			(layer "F.Fab")
		)
		(fp_line
			(start 0.120396 0.2794)
			(end -0.12065 0.2794)
			(stroke
				(width 0.1)
				(type default)
			)
			(layer "F.Fab")
		)
		(fp_line
			(start -0.12065 -0.2794)
			(end 0.12065 -0.2794)
			(stroke
				(width 0.1)
				(type default)
			)
			(layer "F.Fab")
		)
		(fp_line
			(start 0.12065 -0.2794)
			(end 0.12065 -0.3048)
			(stroke
				(width 0.1)
				(type default)
			)
			(layer "F.Fab")
		)
		(fp_line
			(start 0.12065 -0.3048)
			(end 0.67945 -0.3048)
			(stroke
				(width 0.1)
				(type default)
			)
			(layer "F.Fab")
		)
		(fp_line
			(start 0.67945 -0.3048)
			(end 0.67945 0.3048)
			(stroke
				(width 0.1)
				(type default)
			)
			(layer "F.Fab")
		)
		(fp_line
			(start -0.67945 -0.305054)
			(end -0.12065 -0.305054)
			(stroke
				(width 0.1)
				(type default)
			)
			(layer "F.Fab")
		)
		(fp_line
			(start -0.12065 -0.305054)
			(end -0.12065 -0.2794)
			(stroke
				(width 0.1)
				(type default)
			)
			(layer "F.Fab")
		)
		(pad "1" smd circle
			(at -0.40005 0 270)
			(size 0 0)
			(layers "F.Cu" "F.Mask" "F.Paste")
			(net "PVCCINFAON_CPU1")
		)
		(pad "2" smd circle
			(at 0.40005 0 270)
			(size 0 0)
			(layers "F.Cu" "F.Mask" "F.Paste")
			(net "GND")
		)
	)
)
